# S9S_MB_2U (Grand Teton) — schematic netlist excerpt (pin names and nets, part order shuffled) for the footprints in the layout excerpt that follows; sources: Cadence DE-HDL packaged netlist, KiCad conversion of 03242023_DA0F0TMBIJ0_F0T_Motherboard_J_brd_V01_OCP.brd

PR4002  Q_RES  15K 1% EMPTY  pkg 0402LF  page 242 : A = P12V_SCM_OV ; B = GND

(kicad_pcb
	(version 20260206)
	(generator "pcbnew")
	(generator_version "10.0")
	(general
		(thickness 1.6)
		(legacy_teardrops no)
	)
	(paper "A4")
	(title_block
		(title "03242023_DA0F0TMBIJ0_F0T_Motherboard_J_brd_V01_OCP.brd")
		(comment 1 "Grand Teton / footprints 1186-1186 of 6105")
	)
	(layers
		(0 "F.Cu" signal "TOP")
		(4 "In1.Cu" signal "GND")
		(6 "In2.Cu" signal "IN1")
		(8 "In3.Cu" signal "GND1")
		(10 "In4.Cu" signal "IN2")
		(12 "In5.Cu" signal "GND2")
		(14 "In6.Cu" signal "IN3")
		(16 "In7.Cu" signal "GND3")
		(18 "In8.Cu" signal "VCC")
		(20 "In9.Cu" signal "VCC1")
		(22 "In10.Cu" signal "GND4")
		(24 "In11.Cu" signal "IN4")
		(26 "In12.Cu" signal "GND5")
		(28 "In13.Cu" signal "IN5")
		(30 "In14.Cu" signal "GND6")
		(32 "In15.Cu" signal "IN6")
		(34 "In16.Cu" signal "GND7")
		(2 "B.Cu" signal "BOTTOM")
		(9 "F.Adhes" user "F.Adhesive")
		(11 "B.Adhes" user "B.Adhesive")
		(13 "F.Paste" user "Package Geometry/Pastemask Top")
		(15 "B.Paste" user "Package Geometry/Pastemask Bottom")
		(5 "F.SilkS" user "Ref Des/Silkscreen Top")
		(7 "B.SilkS" user "Ref Des/Silkscreen Bottom")
		(1 "F.Mask" user "Board Geometry/Soldermask Top")
		(3 "B.Mask" user "Board Geometry/Soldermask Bottom")
		(17 "Dwgs.User" user "User.Drawings")
		(19 "Cmts.User" user "User.Comments")
		(21 "Eco1.User" user "User.Eco1")
		(23 "Eco2.User" user "User.Eco2")
		(25 "Edge.Cuts" user "Board Geometry/Outline")
		(27 "Margin" user)
		(31 "F.CrtYd" user "Package Geometry/Place Bound Top")
		(29 "B.CrtYd" user "Package Geometry/Place Bound Bottom")
		(35 "F.Fab" user "Ref Des/Assembly Top")
		(33 "B.Fab" user "Ref Des/Assembly Bottom")
	)
	(footprint ""
		(layer "F.Cu")
		(at 185.799222 -22.097492 180)
		(property "Reference" "PR4002"
			(at 0 0 180)
			(layer "F.SilkS")
			(hide yes)
			(effects
				(font
					(size 1.27 1.27)
				)
			)
		)
		(property "Value" ""
			(at 0 0 180)
			(layer "F.Fab")
			(effects
				(font
					(size 1.27 1.27)
				)
			)
		)
		(duplicate_pad_numbers_are_jumpers no)
		(fp_line
			(start 0.7874 0.4064)
			(end -0.7874 0.4064)
			(stroke
				(width 0.1524)
				(type default)
			)
			(layer "F.SilkS")
		)
		(fp_line
			(start 0.7874 -0.4064)
			(end 0.7874 0.4064)
			(stroke
				(width 0.1524)
				(type default)
			)
			(layer "F.SilkS")
		)
		(fp_line
			(start -0.7874 0.4064)
			(end -0.7874 -0.4064)
			(stroke
				(width 0.1524)
				(type default)
			)
			(layer "F.SilkS")
		)
		(fp_line
			(start -0.7874 -0.4064)
			(end 0.7874 -0.4064)
			(stroke
				(width 0.1524)
				(type default)
			)
			(layer "F.SilkS")
		)
		(fp_line
			(start 0.67945 0.3048)
			(end 0.120396 0.3048)
			(stroke
				(width 0.1)
				(type default)
			)
			(layer "F.Fab")
		)
		(fp_line
			(start 0.67945 -0.3048)
			(end 0.67945 0.3048)
			(stroke
				(width 0.1)
				(type default)
			)
			(layer "F.Fab")
		)
		(fp_line
			(start 0.12065 -0.2794)
			(end 0.12065 -0.3048)
			(stroke
				(width 0.1)
				(type default)
			)
			(layer "F.Fab")
		)
		(fp_line
			(start 0.12065 -0.3048)
			(end 0.67945 -0.3048)
			(stroke
				(width 0.1)
				(type default)
			)
			(layer "F.Fab")
		)
		(fp_line
			(start 0.120396 0.3048)
			(end 0.120396 0.2794)
			(stroke
				(width 0.1)
				(type default)
			)
			(layer "F.Fab")
		)
		(fp_line
			(start 0.120396 0.2794)
			(end -0.12065 0.2794)
			(stroke
				(width 0.1)
				(type default)
			)
			(layer "F.Fab")
		)
		(fp_line
			(start -0.12065 0.3048)
			(end -0.67945 0.3048)
			(stroke
				(width 0.1)
				(type default)
			)
			(layer "F.Fab")
		)
		(fp_line
			(start -0.12065 0.2794)
			(end -0.12065 0.3048)
			(stroke
				(width 0.1)
				(type default)
			)
			(layer "F.Fab")
		)
		(fp_line
			(start -0.12065 -0.2794)
			(end 0.12065 -0.2794)
			(stroke
				(width 0.1)
				(type default)
			)
			(layer "F.Fab")
		)
		(fp_line
			(start -0.12065 -0.305054)
			(end -0.12065 -0.2794)
			(stroke
				(width 0.1)
				(type default)
			)
			(layer "F.Fab")
		)
		(fp_line
			(start -0.67945 0.3048)
			(end -0.67945 -0.305054)
			(stroke
				(width 0.1)
				(type default)
			)
			(layer "F.Fab")
		)
		(fp_line
			(start -0.67945 -0.305054)
			(end -0.12065 -0.305054)
			(stroke
				(width 0.1)
				(type default)
			)
			(layer "F.Fab")
		)
		(pad "1" smd circle
			(at -0.40005 0 180)
			(size 0 0)
			(layers "F.Cu" "F.Mask" "F.Paste")
			(net "P12V_SCM_OV")
		)
		(pad "2" smd circle
			(at 0.40005 0 180)
			(size 0 0)
			(layers "F.Cu" "F.Mask" "F.Paste")
			(net "GND")
		)
	)
)
